(kicad_pcb
	(version 20260206)
	(generator "pcbnew")
	(generator_version "10.0")
	(general
		(thickness 1.6)
		(legacy_teardrops no)
	)
	(paper "A4")
	(title_block
		(title "Wiwynn_Tioga_Pass_MB.brd")
		(comment 1 "Tioga Pass / footprints 15-22 of 4770")
	)
	(layers
		(0 "F.Cu" signal "TOP")
		(4 "In1.Cu" signal "L2GND")
		(6 "In2.Cu" signal "L3")
		(8 "In3.Cu" signal "L4GND")
		(10 "In4.Cu" signal "L5")
		(12 "In5.Cu" signal "L6GND")
		(14 "In6.Cu" signal "L7VCC")
		(16 "In7.Cu" signal "L8VCC")
		(18 "In8.Cu" signal "L9GND")
		(20 "In9.Cu" signal "L10")
		(22 "In10.Cu" signal "L11GND")
		(24 "In11.Cu" signal "L12")
		(26 "In12.Cu" signal "L13GND")
		(2 "B.Cu" signal "BOTTOM")
		(9 "F.Adhes" user "F.Adhesive")
		(11 "B.Adhes" user "B.Adhesive")
		(13 "F.Paste" user "Package Geometry/Pastemask Top")
		(15 "B.Paste" user "Package Geometry/Pastemask Bottom")
		(5 "F.SilkS" user "Ref Des/Silkscreen Top")
		(7 "B.SilkS" user "Ref Des/Silkscreen Bottom")
		(1 "F.Mask" user "Board Geometry/Soldermask Top")
		(3 "B.Mask" user "Board Geometry/Soldermask Bottom")
		(17 "Dwgs.User" user "User.Drawings")
		(19 "Cmts.User" user "User.Comments")
		(21 "Eco1.User" user "User.Eco1")
		(23 "Eco2.User" user "User.Eco2")
		(25 "Edge.Cuts" user "Board Geometry/Outline")
		(27 "Margin" user)
		(31 "F.CrtYd" user "Package Geometry/Place Bound Top")
		(29 "B.CrtYd" user "Package Geometry/Place Bound Bottom")
		(35 "F.Fab" user "Ref Des/Assembly Top")
		(33 "B.Fab" user "Ref Des/Assembly Bottom")
	)
	(footprint ""
		(layer "F.Cu")
		(at 392.303 -71.0565 180)
		(property "Reference" "C7E10"
			(at 0 0 180)
			(layer "F.SilkS")
			(hide yes)
			(effects
				(font
					(size 1.27 1.27)
				)
			)
		)
		(property "Value" ""
			(at 0 0 180)
			(layer "F.Fab")
			(effects
				(font
					(size 1.27 1.27)
				)
			)
		)
		(duplicate_pad_numbers_are_jumpers no)
		(fp_poly
			(pts
				(xy 0.3048 -0.1016) (xy 0.3048 0.9906) (xy -0.3048 0.9906) (xy -0.3048 -0.1016)
			)
			(stroke
				(width 0)
				(type default)
			)
			(fill no)
			(layer "F.CrtYd")
		)
		(fp_line
			(start 0.3048 0.9906)
			(end 0.3048 -0.1016)
			(stroke
				(width 0.1)
				(type default)
			)
			(layer "F.Fab")
		)
		(fp_line
			(start 0.3048 -0.1016)
			(end -0.3048 -0.1016)
			(stroke
				(width 0.1)
				(type default)
			)
			(layer "F.Fab")
		)
		(fp_line
			(start -0.3048 0.9906)
			(end 0.3048 0.9906)
			(stroke
				(width 0.1)
				(type default)
			)
			(layer "F.Fab")
		)
		(fp_line
			(start -0.3048 -0.1016)
			(end -0.3048 0.9906)
			(stroke
				(width 0.1)
				(type default)
			)
			(layer "F.Fab")
		)
		(pad "1" smd rect
			(at 0 0 180)
			(size 0.508 0.508)
			(layers "F.Cu" "F.Mask" "F.Paste")
			(net "PWRGD_P5V_STBY_R")
		)
		(pad "2" smd rect
			(at 0 0.889 180)
			(size 0.508 0.508)
			(layers "F.Cu" "F.Mask" "F.Paste")
			(net "GND")
		)
		(zone
			(layer "F.Cu")
			(hatch none 0.5)
			(connect_pads
				(clearance 0)
			)
			(min_thickness 0.25)
			(keepout
				(tracks not_allowed)
				(vias allowed)
				(pads allowed)
				(copperpour not_allowed)
				(footprints allowed)
			)
			(placement
				(enabled no)
				(sheetname "")
			)
			(fill
				(thermal_gap 0.5)
				(thermal_bridge_width 0.5)
				(island_removal_mode 0)
			)
			(polygon
				(pts
					(xy 392.557 -71.6915) (xy 392.049 -71.6915) (xy 392.049 -71.3105) (xy 392.557 -71.3105)
				)
			)
		)
		(zone
			(layer "F.Cu")
			(hatch none 0.5)
			(connect_pads
				(clearance 0)
			)
			(min_thickness 0.25)
			(keepout
				(tracks allowed)
				(vias not_allowed)
				(pads allowed)
				(copperpour not_allowed)
				(footprints allowed)
			)
			(placement
				(enabled no)
				(sheetname "")
			)
			(fill
				(thermal_gap 0.5)
				(thermal_bridge_width 0.5)
				(island_removal_mode 0)
			)
			(polygon
				(pts
					(xy 392.557 -71.3105) (xy 392.049 -71.3105) (xy 392.049 -71.6915) (xy 392.557 -71.6915)
				)
			)
		)
	)
	(footprint ""
		(layer "F.Cu")
		(at 464.7946 -21.3233)
		(property "Reference" "R8F10"
			(at 0 0 0)
			(layer "F.SilkS")
			(hide yes)
			(effects
				(font
					(size 1.27 1.27)
				)
			)
		)
		(property "Value" ""
			(at 0 0 0)
			(layer "F.Fab")
			(effects
				(font
					(size 1.27 1.27)
				)
			)
		)
		(duplicate_pad_numbers_are_jumpers no)
		(fp_poly
			(pts
				(xy -0.2794 -0.1016) (xy 0.2794 -0.1016) (xy 0.2794 0.9906) (xy -0.2794 0.9906)
			)
			(stroke
				(width 0)
				(type default)
			)
			(fill no)
			(layer "F.CrtYd")
		)
		(fp_line
			(start -0.2794 -0.1016)
			(end -0.2794 0.9906)
			(stroke
				(width 0.1)
				(type default)
			)
			(layer "F.Fab")
		)
		(fp_line
			(start -0.2794 0.9906)
			(end 0.2794 0.9906)
			(stroke
				(width 0.1)
				(type default)
			)
			(layer "F.Fab")
		)
		(fp_line
			(start 0.2794 -0.1016)
			(end -0.2794 -0.1016)
			(stroke
				(width 0.1)
				(type default)
			)
			(layer "F.Fab")
		)
		(fp_line
			(start 0.2794 0.9906)
			(end 0.2794 -0.1016)
			(stroke
				(width 0.1)
				(type default)
			)
			(layer "F.Fab")
		)
		(pad "1" smd rect
			(at 0 0)
			(size 0.508 0.508)
			(layers "F.Cu" "F.Mask" "F.Paste")
			(net "PWRGD_P3V3_STBY_R")
		)
		(pad "2" smd rect
			(at 0 0.889)
			(size 0.508 0.508)
			(layers "F.Cu" "F.Mask" "F.Paste")
			(net "PWRGD_P3V3_STBY")
		)
		(zone
			(layer "F.Cu")
			(hatch none 0.5)
			(connect_pads
				(clearance 0)
			)
			(min_thickness 0.25)
			(keepout
				(tracks allowed)
				(vias not_allowed)
				(pads allowed)
				(copperpour not_allowed)
				(footprints allowed)
			)
			(placement
				(enabled no)
				(sheetname "")
			)
			(fill
				(thermal_gap 0.5)
				(thermal_bridge_width 0.5)
				(island_removal_mode 0)
			)
			(polygon
				(pts
					(xy 464.5406 -21.0693) (xy 465.0486 -21.0693) (xy 465.0486 -20.6883) (xy 464.5406 -20.6883)
				)
			)
		)
		(zone
			(layer "F.Cu")
			(hatch none 0.5)
			(connect_pads
				(clearance 0)
			)
			(min_thickness 0.25)
			(keepout
				(tracks not_allowed)
				(vias allowed)
				(pads allowed)
				(copperpour not_allowed)
				(footprints allowed)
			)
			(placement
				(enabled no)
				(sheetname "")
			)
			(fill
				(thermal_gap 0.5)
				(thermal_bridge_width 0.5)
				(island_removal_mode 0)
			)
			(polygon
				(pts
					(xy 464.5406 -20.6883) (xy 465.0486 -20.6883) (xy 465.0486 -21.0693) (xy 464.5406 -21.0693)
				)
			)
		)
	)
	(footprint ""
		(layer "F.Cu")
		(at 109.522768 -79.6036 180)
		(property "Reference" "C3D5"
			(at 0 0 180)
			(layer "F.SilkS")
			(hide yes)
			(effects
				(font
					(size 1.27 1.27)
				)
			)
		)
		(property "Value" ""
			(at 0 0 180)
			(layer "F.Fab")
			(effects
				(font
					(size 1.27 1.27)
				)
			)
		)
		(duplicate_pad_numbers_are_jumpers no)
		(fp_poly
			(pts
				(xy -0.4953 -0.2032) (xy 0.4953 -0.2032) (xy 0.4953 1.6002) (xy -0.4953 1.6002)
			)
			(stroke
				(width 0)
				(type default)
			)
			(fill no)
			(layer "F.CrtYd")
		)
		(fp_line
			(start 0.4953 1.6002)
			(end -0.4953 1.6002)
			(stroke
				(width 0.1)
				(type default)
			)
			(layer "F.Fab")
		)
		(fp_line
			(start 0.4953 -0.2032)
			(end 0.4953 1.6002)
			(stroke
				(width 0.1)
				(type default)
			)
			(layer "F.Fab")
		)
		(fp_line
			(start -0.4953 1.6002)
			(end -0.4953 -0.2032)
			(stroke
				(width 0.1)
				(type default)
			)
			(layer "F.Fab")
		)
		(fp_line
			(start -0.4953 -0.2032)
			(end 0.4953 -0.2032)
			(stroke
				(width 0.1)
				(type default)
			)
			(layer "F.Fab")
		)
		(pad "1" smd rect
			(at 0 0 180)
			(size 0.762 0.889)
			(layers "F.Cu" "F.Mask" "F.Paste")
			(net "PVCCMCP_CPU1")
		)
		(pad "2" smd rect
			(at 0 1.397 180)
			(size 0.762 0.889)
			(layers "F.Cu" "F.Mask" "F.Paste")
			(net "GND")
		)
		(zone
			(layer "F.Cu")
			(hatch none 0.5)
			(connect_pads
				(clearance 0)
			)
			(min_thickness 0.25)
			(keepout
				(tracks not_allowed)
				(vias allowed)
				(pads allowed)
				(copperpour not_allowed)
				(footprints allowed)
			)
			(placement
				(enabled no)
				(sheetname "")
			)
			(fill
				(thermal_gap 0.5)
				(thermal_bridge_width 0.5)
				(island_removal_mode 0)
			)
			(polygon
				(pts
					(xy 109.903768 -80.0481) (xy 109.141768 -80.0481) (xy 109.141768 -80.5561) (xy 109.903768 -80.5561)
				)
			)
		)
	)
	(footprint ""
		(layer "F.Cu")
		(at 282.030424 -71.460614 -90)
		(property "Reference" "R6D11"
			(at 0 0 270)
			(layer "F.SilkS")
			(hide yes)
			(effects
				(font
					(size 1.27 1.27)
				)
			)
		)
		(property "Value" ""
			(at 0 0 270)
			(layer "F.Fab")
			(effects
				(font
					(size 1.27 1.27)
				)
			)
		)
		(duplicate_pad_numbers_are_jumpers no)
		(fp_rect
			(start 0.2794 0.9906)
			(end -0.2794 -0.1016)
			(stroke
				(width 0)
				(type default)
			)
			(fill no)
			(layer "F.CrtYd")
		)
		(fp_line
			(start -0.2794 0.9906)
			(end 0.2794 0.9906)
			(stroke
				(width 0.1)
				(type default)
			)
			(layer "F.Fab")
		)
		(fp_line
			(start 0.2794 0.9906)
			(end 0.2794 -0.1016)
			(stroke
				(width 0.1)
				(type default)
			)
			(layer "F.Fab")
		)
		(fp_line
			(start -0.2794 -0.1016)
			(end -0.2794 0.9906)
			(stroke
				(width 0.1)
				(type default)
			)
			(layer "F.Fab")
		)
		(fp_line
			(start 0.2794 -0.1016)
			(end -0.2794 -0.1016)
			(stroke
				(width 0.1)
				(type default)
			)
			(layer "F.Fab")
		)
		(pad "1" smd rect
			(at 0 0 270)
			(size 0.508 0.508)
			(layers "F.Cu" "F.Mask" "F.Paste")
			(net "A_CPU0_UPI01_RBIAS")
		)
		(pad "2" smd rect
			(at 0 0.889 270)
			(size 0.508 0.508)
			(layers "F.Cu" "F.Mask" "F.Paste")
			(net "GND")
		)
		(zone
			(layer "F.Cu")
			(hatch none 0.5)
			(connect_pads
				(clearance 0)
			)
			(min_thickness 0.25)
			(keepout
				(tracks not_allowed)
				(vias allowed)
				(pads allowed)
				(copperpour not_allowed)
				(footprints allowed)
			)
			(placement
				(enabled no)
				(sheetname "")
			)
			(fill
				(thermal_gap 0.5)
				(thermal_bridge_width 0.5)
				(island_removal_mode 0)
			)
			(polygon
				(pts
					(xy 281.395424 -71.206614) (xy 281.776424 -71.206614) (xy 281.776424 -71.714614) (xy 281.395424 -71.714614)
				)
			)
		)
		(zone
			(layer "F.Cu")
			(hatch none 0.5)
			(connect_pads
				(clearance 0)
			)
			(min_thickness 0.25)
			(keepout
				(tracks allowed)
				(vias not_allowed)
				(pads allowed)
				(copperpour not_allowed)
				(footprints allowed)
			)
			(placement
				(enabled no)
				(sheetname "")
			)
			(fill
				(thermal_gap 0.5)
				(thermal_bridge_width 0.5)
				(island_removal_mode 0)
			)
			(polygon
				(pts
					(xy 281.395424 -71.206614) (xy 281.776424 -71.206614) (xy 281.776424 -71.714614) (xy 281.395424 -71.714614)
				)
			)
		)
	)
	(footprint ""
		(layer "F.Cu")
		(at 380.538228 -154.247596)
		(property "Reference" "C7A39"
			(at 0 0 0)
			(layer "F.SilkS")
			(hide yes)
			(effects
				(font
					(size 1.27 1.27)
				)
			)
		)
		(property "Value" ""
			(at 0 0 0)
			(layer "F.Fab")
			(effects
				(font
					(size 1.27 1.27)
				)
			)
		)
		(duplicate_pad_numbers_are_jumpers no)
		(fp_poly
			(pts
				(xy 0.3048 -0.1016) (xy 0.3048 0.9906) (xy -0.3048 0.9906) (xy -0.3048 -0.1016)
			)
			(stroke
				(width 0)
				(type default)
			)
			(fill no)
			(layer "F.CrtYd")
		)
		(fp_line
			(start -0.3048 -0.1016)
			(end -0.3048 0.9906)
			(stroke
				(width 0.1)
				(type default)
			)
			(layer "F.Fab")
		)
		(fp_line
			(start -0.3048 0.9906)
			(end 0.3048 0.9906)
			(stroke
				(width 0.1)
				(type default)
			)
			(layer "F.Fab")
		)
		(fp_line
			(start 0.3048 -0.1016)
			(end -0.3048 -0.1016)
			(stroke
				(width 0.1)
				(type default)
			)
			(layer "F.Fab")
		)
		(fp_line
			(start 0.3048 0.9906)
			(end 0.3048 -0.1016)
			(stroke
				(width 0.1)
				(type default)
			)
			(layer "F.Fab")
		)
		(pad "1" smd rect
			(at 0 0)
			(size 0.508 0.508)
			(layers "F.Cu" "F.Mask" "F.Paste")
			(net "VR_FET_SW_P12V_STBY_PVDDQ_DEF")
		)
		(pad "2" smd rect
			(at 0 0.889)
			(size 0.508 0.508)
			(layers "F.Cu" "F.Mask" "F.Paste")
			(net "GND")
		)
		(zone
			(layer "F.Cu")
			(hatch none 0.5)
			(connect_pads
				(clearance 0)
			)
			(min_thickness 0.25)
			(keepout
				(tracks allowed)
				(vias not_allowed)
				(pads allowed)
				(copperpour not_allowed)
				(footprints allowed)
			)
			(placement
				(enabled no)
				(sheetname "")
			)
			(fill
				(thermal_gap 0.5)
				(thermal_bridge_width 0.5)
				(island_removal_mode 0)
			)
			(polygon
				(pts
					(xy 380.284228 -153.993596) (xy 380.792228 -153.993596) (xy 380.792228 -153.612596) (xy 380.284228 -153.612596)
				)
			)
		)
		(zone
			(layer "F.Cu")
			(hatch none 0.5)
			(connect_pads
				(clearance 0)
			)
			(min_thickness 0.25)
			(keepout
				(tracks not_allowed)
				(vias allowed)
				(pads allowed)
				(copperpour not_allowed)
				(footprints allowed)
			)
			(placement
				(enabled no)
				(sheetname "")
			)
			(fill
				(thermal_gap 0.5)
				(thermal_bridge_width 0.5)
				(island_removal_mode 0)
			)
			(polygon
				(pts
					(xy 380.284228 -153.612596) (xy 380.792228 -153.612596) (xy 380.792228 -153.993596) (xy 380.284228 -153.993596)
				)
			)
		)
	)
	(footprint ""
		(layer "F.Cu")
		(at 266.397232 -140.208 90)
		(property "Reference" "C5A16"
			(at 1.848866 0.752348 90)
			(unlocked yes)
			(layer "F.SilkS")
			(effects
				(font
					(size 1.27 0.9652)
					(thickness 0.1524)
				)
			)
		)
		(property "Value" ""
			(at 0 0 90)
			(layer "F.Fab")
			(effects
				(font
					(size 1.27 1.27)
				)
			)
		)
		(duplicate_pad_numbers_are_jumpers no)
		(fp_rect
			(start -0.500126 1.598422)
			(end 0.500126 -0.201422)
			(stroke
				(width 0)
				(type default)
			)
			(fill no)
			(layer "F.CrtYd")
		)
		(fp_line
			(start 0.500126 -0.201422)
			(end 0.500126 1.598422)
			(stroke
				(width 0.1)
				(type default)
			)
			(layer "F.Fab")
		)
		(fp_line
			(start -0.500126 -0.201422)
			(end 0.500126 -0.201422)
			(stroke
				(width 0.1)
				(type default)
			)
			(layer "F.Fab")
		)
		(fp_line
			(start 0.500126 1.598422)
			(end -0.500126 1.598422)
			(stroke
				(width 0.1)
				(type default)
			)
			(layer "F.Fab")
		)
		(fp_line
			(start -0.500126 1.598422)
			(end -0.500126 -0.201422)
			(stroke
				(width 0.1)
				(type default)
			)
			(layer "F.Fab")
		)
		(pad "1" smd rect
			(at 0 0)
			(size 0.889 0.9906)
			(layers "F.Cu" "F.Mask" "F.Paste")
			(net "PVDDQ_DEF")
		)
		(pad "2" smd rect
			(at 0 1.397)
			(size 0.889 0.9906)
			(layers "F.Cu" "F.Mask" "F.Paste")
			(net "GND")
		)
		(zone
			(layer "F.Cu")
			(hatch none 0.5)
			(connect_pads
				(clearance 0)
			)
			(min_thickness 0.25)
			(keepout
				(tracks allowed)
				(vias not_allowed)
				(pads allowed)
				(copperpour not_allowed)
				(footprints allowed)
			)
			(placement
				(enabled no)
				(sheetname "")
			)
			(fill
				(thermal_gap 0.5)
				(thermal_bridge_width 0.5)
				(island_removal_mode 0)
			)
			(polygon
				(pts
					(xy 267.349732 -139.7127) (xy 267.349732 -140.7033) (xy 266.841732 -140.7033) (xy 266.841732 -139.7127)
				)
			)
		)
		(zone
			(layer "F.Cu")
			(hatch none 0.5)
			(connect_pads
				(clearance 0)
			)
			(min_thickness 0.25)
			(keepout
				(tracks not_allowed)
				(vias allowed)
				(pads allowed)
				(copperpour not_allowed)
				(footprints allowed)
			)
			(placement
				(enabled no)
				(sheetname "")
			)
			(fill
				(thermal_gap 0.5)
				(thermal_bridge_width 0.5)
				(island_removal_mode 0)
			)
			(polygon
				(pts
					(xy 267.349732 -139.7127) (xy 267.349732 -140.7033) (xy 266.841732 -140.7033) (xy 266.841732 -139.7127)
				)
			)
		)
	)
	(footprint ""
		(layer "F.Cu")
		(at 23.114 -79.629 -90)
		(property "Reference" "R1D27"
			(at 0 0 270)
			(layer "F.SilkS")
			(hide yes)
			(effects
				(font
					(size 1.27 1.27)
				)
			)
		)
		(property "Value" ""
			(at 0 0 270)
			(layer "F.Fab")
			(effects
				(font
					(size 1.27 1.27)
				)
			)
		)
		(duplicate_pad_numbers_are_jumpers no)
		(fp_rect
			(start -0.2794 -0.1016)
			(end 0.2794 0.9906)
			(stroke
				(width 0)
				(type default)
			)
			(fill no)
			(layer "F.CrtYd")
		)
		(fp_line
			(start -0.2794 0.9906)
			(end 0.2794 0.9906)
			(stroke
				(width 0.1)
				(type default)
			)
			(layer "F.Fab")
		)
		(fp_line
			(start 0.2794 0.9906)
			(end 0.2794 -0.1016)
			(stroke
				(width 0.1)
				(type default)
			)
			(layer "F.Fab")
		)
		(fp_line
			(start -0.2794 -0.1016)
			(end -0.2794 0.9906)
			(stroke
				(width 0.1)
				(type default)
			)
			(layer "F.Fab")
		)
		(fp_line
			(start 0.2794 -0.1016)
			(end -0.2794 -0.1016)
			(stroke
				(width 0.1)
				(type default)
			)
			(layer "F.Fab")
		)
		(pad "1" smd rect
			(at 0 0 270)
			(size 0.508 0.508)
			(layers "F.Cu" "F.Mask" "F.Paste")
			(net "A_HSC_VCAP")
		)
		(pad "2" smd rect
			(at 0 0.889 270)
			(size 0.508 0.508)
			(layers "F.Cu" "F.Mask" "F.Paste")
			(net "FM_P12V_HSC_ADR2")
		)
		(zone
			(layer "F.Cu")
			(hatch none 0.5)
			(connect_pads
				(clearance 0)
			)
			(min_thickness 0.25)
			(keepout
				(tracks not_allowed)
				(vias allowed)
				(pads allowed)
				(copperpour not_allowed)
				(footprints allowed)
			)
			(placement
				(enabled no)
				(sheetname "")
			)
			(fill
				(thermal_gap 0.5)
				(thermal_bridge_width 0.5)
				(island_removal_mode 0)
			)
			(polygon
				(pts
					(xy 22.86 -79.883) (xy 22.479 -79.883) (xy 22.479 -79.375) (xy 22.86 -79.375)
				)
			)
		)
		(zone
			(layer "F.Cu")
			(hatch none 0.5)
			(connect_pads
				(clearance 0)
			)
			(min_thickness 0.25)
			(keepout
				(tracks allowed)
				(vias not_allowed)
				(pads allowed)
				(copperpour not_allowed)
				(footprints allowed)
			)
			(placement
				(enabled no)
				(sheetname "")
			)
			(fill
				(thermal_gap 0.5)
				(thermal_bridge_width 0.5)
				(island_removal_mode 0)
			)
			(polygon
				(pts
					(xy 22.86 -79.883) (xy 22.479 -79.883) (xy 22.479 -79.375) (xy 22.86 -79.375)
				)
			)
		)
	)
	(footprint ""
		(layer "F.Cu")
		(at 339.1154 -128.3208)
		(property "Reference" "C7B9"
			(at 0 0 0)
			(layer "F.SilkS")
			(hide yes)
			(effects
				(font
					(size 1.27 1.27)
				)
			)
		)
		(property "Value" ""
			(at 0 0 0)
			(layer "F.Fab")
			(effects
				(font
					(size 1.27 1.27)
				)
			)
		)
		(duplicate_pad_numbers_are_jumpers no)
		(fp_poly
			(pts
				(xy 0.3048 -0.1016) (xy 0.3048 0.9906) (xy -0.3048 0.9906) (xy -0.3048 -0.1016)
			)
			(stroke
				(width 0)
				(type default)
			)
			(fill no)
			(layer "F.CrtYd")
		)
		(fp_line
			(start -0.3048 -0.1016)
			(end -0.3048 0.9906)
			(stroke
				(width 0.1)
				(type default)
			)
			(layer "F.Fab")
		)
		(fp_line
			(start -0.3048 0.9906)
			(end 0.3048 0.9906)
			(stroke
				(width 0.1)
				(type default)
			)
			(layer "F.Fab")
		)
		(fp_line
			(start 0.3048 -0.1016)
			(end -0.3048 -0.1016)
			(stroke
				(width 0.1)
				(type default)
			)
			(layer "F.Fab")
		)
		(fp_line
			(start 0.3048 0.9906)
			(end 0.3048 -0.1016)
			(stroke
				(width 0.1)
				(type default)
			)
			(layer "F.Fab")
		)
		(pad "1" smd rect
			(at 0 0)
			(size 0.508 0.508)
			(layers "F.Cu" "F.Mask" "F.Paste")
			(net "FM_PVPP_CPU0_EN")
		)
		(pad "2" smd rect
			(at 0 0.889)
			(size 0.508 0.508)
			(layers "F.Cu" "F.Mask" "F.Paste")
			(net "AGND_PVPP_DEF")
		)
		(zone
			(layer "F.Cu")
			(hatch none 0.5)
			(connect_pads
				(clearance 0)
			)
			(min_thickness 0.25)
			(keepout
				(tracks allowed)
				(vias not_allowed)
				(pads allowed)
				(copperpour not_allowed)
				(footprints allowed)
			)
			(placement
				(enabled no)
				(sheetname "")
			)
			(fill
				(thermal_gap 0.5)
				(thermal_bridge_width 0.5)
				(island_removal_mode 0)
			)
			(polygon
				(pts
					(xy 338.8614 -128.0668) (xy 339.3694 -128.0668) (xy 339.3694 -127.6858) (xy 338.8614 -127.6858)
				)
			)
		)
		(zone
			(layer "F.Cu")
			(hatch none 0.5)
			(connect_pads
				(clearance 0)
			)
			(min_thickness 0.25)
			(keepout
				(tracks not_allowed)
				(vias allowed)
				(pads allowed)
				(copperpour not_allowed)
				(footprints allowed)
			)
			(placement
				(enabled no)
				(sheetname "")
			)
			(fill
				(thermal_gap 0.5)
				(thermal_bridge_width 0.5)
				(island_removal_mode 0)
			)
			(polygon
				(pts
					(xy 338.8614 -127.6858) (xy 339.3694 -127.6858) (xy 339.3694 -128.0668) (xy 338.8614 -128.0668)
				)
			)
		)
	)
)
